Testpoint Report Status for Project:16318-2

Total # of Nets  : 1068

Number of nets with "No_Test" property      :   0
Number of nets with testpoints assigned >1  :   14
Number of nets with testpoints assigned =1  :   783
Number of nets with testpoints assigned =0  :   271

Percent (All nets)                              :  74.63%
Percent (All nets Excluded "No_Test" property)  :  74.63%

BMC_EXT1_LED_Y                         2
COMP_FAST_THROTTLE_N                   2
GND                                    3
P1V2_STBY                              2
P1V8                                   2
P3V3_STBY                              2
P3V3_STBY_OUT                          2
P5V_STBY                               3
PWRBTN_OUT_N                           2
PWRGD_P1V2_STBY                        2
SAS0_AVDD                              2
TPS74801_P1V2_STBY_OUT                 2
UART_SERCLK                            2
USB_CONN_GND                           2

50M_CLK_OE                             1
ADCAV33                                1
ADCVREFFN                              1
ADCVREFFP                              1
ADCVREXT                               1
ADC_12V                                1
ADC_P0V975                             1
ADC_P1V15_STBY                         1
ADC_P1V2_STBY                          1
ADC_P1V5                               1
ADC_P1V8                               1
ADC_P1V8_STBY                          1
ADC_P2V5_STBY                          1
ADC_P3V3                               1
ADC_P3V3_STBY                          1
ADC_P5V_STBY                           1
ADM1278_HS_N                           1
ADM1278_HS_P                           1
AGND_CURRENT_MON                       1
AGND_P0V975                            1
AGND_P1V8_STBY                         1
AGND_P3V3_STBY                         1
AGND_P5V                               1
AVSO_IDDTN18                           1
AVSO_VREF                              1
BMC0_JTAG_RTCK                         1
BMC0_SRST_N                            1
BMC_ENTEST                             1
BMC_EXT2_LED_Y                         1
BMC_EXTRST_N                           1
BMC_GPIOS4                             1
BMC_GPIOS5                             1
BMC_GPIOS6                             1
BMC_GPIOS7                             1
BMC_GPIOY0                             1
BMC_GPIOY1                             1
BMC_GPIOY2                             1
BMC_GPIOY3                             1
BMC_GPIOZ4                             1
BMC_GPIOZ5                             1
BMC_GPIOZ6                             1
BMC_HBLED                              1
BMC_HBLED_R                            1
BMC_LOC_HB                             1
BMC_LOC_HEARTBEAT                      1
BMC_ML_PWR_BLUE_LED                    1
BMC_ML_PWR_BLUE_LED_L                  1
BMC_ML_PWR_BLUE_LED_R                  1
BMC_ML_PWR_YELLOW_LED                  1
BMC_ML_PWR_YELLOW_LED_R                1
BMC_PEREXT                             1
BMC_RGMII_A4_D3                        1
BMC_RGMII_C2_C3_D1_D2_E6               1
BMC_RMT_HB                             1
BMC_RMT_HEARTBEAT                      1
BMC_SELF_HW_RST                        1
BMC_SELF_HW_RST_D                      1
BMC_SMB10_CLK                          1
BMC_SMB10_DAT                          1
BMC_SMB11_CLK                          1
BMC_SMB11_DAT                          1
BMC_SMB12_CLK                          1
BMC_SMB12_DAT                          1
BMC_SMB13_CLK                          1
BMC_SMB13_DAT                          1
BMC_SMB14_CLK                          1
BMC_SMB14_DAT                          1
BMC_SMB1_CLK                           1
BMC_SMB1_DAT                           1
BMC_SMB2_CLK                           1
BMC_SMB2_DAT                           1
BMC_SMB3_CLK                           1
BMC_SMB3_DAT                           1
BMC_SMB4_CLK                           1
BMC_SMB4_DAT                           1
BMC_SMB5_CLK                           1
BMC_SMB5_DAT                           1
BMC_SMB6_CLK                           1
BMC_SMB6_DAT                           1
BMC_SMB7_CLK                           1
BMC_SMB7_DAT                           1
BMC_SMB8_CLK                           1
BMC_SMB8_DAT                           1
BMC_SMB9_CLK                           1
BMC_SMB9_DAT                           1
BMC_SPI_CLK                            1
BMC_SPI_CLK_R                          1
BMC_SPI_MISO_R                         1
BMC_SPI_MOSI                           1
BMC_SPI_MOSI_R                         1
BMC_TO_EXP_RESET_N                     1
BMC_TO_EXP_RESET_OUT                   1
BMC_TO_EXP_RESET_OUT_R                 1
BMC_TPM_RST_N                          1
BMC_UART_SEL_IN                        1
BMC_UART_SEL_OUT                       1
BOARD_REV_0                            1
BOARD_REV_1                            1
BOARD_REV_2                            1
BYTE_N                                 1
CFG_SEL0                               1
CFG_SEL1                               1
CLK_50M_BMC_NCSI                       1
COMP_POWER_FAIL_N                      1
COMP_POWER_FAIL_R_N                    1
COMP_PWR_BTN_N                         1
COMP_PWR_BTN_R_N                       1
COMP_PWR_EN                            1
COMP_PWR_EN_R                          1
COMP_SPARE_0                           1
COMP_SPARE_0_R                         1
COMP_SPARE_1                           1
COMP_SPARE_1_R                         1
COMP_TO_BMC_RESET                      1
COMP_TO_BMC_RESET_N_OUT                1
COMP_TO_BMC_RESET_R                    1
CONN_A_PRSNTA                          1
CP_DONE                                1
CRFILT                                 1
DACAV33                                1
DACRSET                                1
DB_PRSNT_BMC_N                         1
DDR_VREF                               1
DEBUG_CARD_PRSNT                       1
DEBUG_GPIO_BMC_1                       1
DEBUG_GPIO_BMC_2                       1
DEBUG_GPIO_BMC_3                       1
DEBUG_GPIO_BMC_4                       1
DEBUG_GPIO_BMC_5                       1
DEBUG_GPIO_BMC_6                       1
DEBUG_GPIO_BMC_R_1                     1
DEBUG_GPIO_BMC_R_2                     1
DEBUG_GPIO_BMC_R_3                     1
DEBUG_GPIO_BMC_R_4                     1
DEBUG_GPIO_BMC_R_5                     1
DEBUG_GPIO_BMC_R_6                     1
DEBUG_HDR_UART_SEL                     1
DEBUG_RST_BTN_N                        1
DEBUG_RST_BTN_N_R                      1
DEBUG_UART_IOM_RX                      1
DEBUG_UART_IOM_TX                      1
DPB_MISC_ALERT                         1
DPB_MISC_ALERT_OUT                     1
DPB_MISC_ALERT_OUT_R                   1
DPB_MISC_ALERT_O_R                     1
D_FLIP_CLR#                            1
D_FLIP_D                               1
D_FLIP_PRE#                            1
D_FLIP_Q                               1
D_FLIP_Q#                              1
EEPROM_A0                              1
EEPROM_A1                              1
EEPROM_A2                              1
EEPROM_WP                              1
ENCL_FAULT_LED                         1
ENCL_FAULT_LED_R                       1
EXP_SPARE_0                            1
EXP_SPARE_0_R                          1
EXP_SPARE_1                            1
EXP_SPARE_1_R                          1
EXP_UART_EN                            1
EXP_UART_EN_R                          1
EXT1_CONN_GND                          1
EXT1_LED_BLUE                          1
EXT1_LED_BLUE_D                        1
EXT1_LED_BLUE_G2                       1
EXT1_LED_BLUE_G_Q24                    1
EXT1_LED_YELLOW                        1
EXT1_LED_YELLOW_D                      1
EXT1_LED_YELLOW_D1                     1
EXT1_LED_YELLOW_G1                     1
EXT2_CONN_GND                          1
EXT2_LED_BLUE                          1
EXT2_LED_BLUE_D                        1
EXT2_LED_BLUE_G2                       1
EXT2_LED_BLUE_G_Q27                    1
EXT2_LED_YELLOW                        1
EXT2_LED_YELLOW_D                      1
EXT2_LED_YELLOW_D1                     1
EXT2_LED_YELLOW_G1                     1
FAN_PWM0_BMC                           1
FAN_PWM1_BMC                           1
FLA0_WP_N                              1
FLA0_WP_N_R                            1
FLA1_WP_N                              1
FLA_CS_0                               1
FLA_CS_0_R                             1
FLA_CS_1                               1
FLA_CS_1_R                             1
FM_BMC_RESET_N                         1
FM_TPM_PRSNT_N                         1
FM_TPM_PRSNT_RST                       1
FM_TPM_PRSNT_RST_N                     1
FM_TPM_PRSNT_RST_N_C                   1
FM_TPM_PRSNT_RST_N_R                   1
FP_PWRBTN                              1
FP_PWR_BTN_N                           1
FP_PWR_BTN_N_R                         1
FP_RESET_RC_N                          1
FP_RETBTN                              1
GND_SEN                                1
HM40ADC_VDDA                           1
HSW_SCL                                1
HSW_SDA                                1
I2C_BMC_COMP_ALERT_N                   1
I2C_BMC_COMP_ALERT_N_R                 1
I2C_BMC_COMP_SCL                       1
I2C_BMC_COMP_SCL_OUT                   1
I2C_BMC_COMP_SCL_R                     1
I2C_BMC_COMP_SDA                       1
I2C_BMC_COMP_SDA_OUT                   1
I2C_BMC_COMP_SDA_R                     1
I2C_COMP_ALERT_N                       1
I2C_DEBUG_SCL                          1
I2C_DEBUG_SCL_L                        1
I2C_DEBUG_SDA                          1
I2C_DEBUG_SDA_L                        1
I2C_DPB_MISC_SCL                       1
I2C_DPB_MISC_SCL_OUT                   1
I2C_DPB_MISC_SCL_R                     1
I2C_DPB_MISC_SDA                       1
I2C_DPB_MISC_SDA_OUT                   1
I2C_DPB_MISC_SDA_R                     1
I2C_DPB_SCL                            1
I2C_DPB_SCL_OUT                        1
I2C_DPB_SCL_R                          1
I2C_DPB_SDA                            1
I2C_DPB_SDA_OUT                        1
I2C_DPB_SDA_R                          1
I2C_EXP_LOC_SCL                        1
I2C_EXP_LOC_SCL_OUT                    1
I2C_EXP_LOC_SCL_R                      1
I2C_EXP_LOC_SDA                        1
I2C_EXP_LOC_SDA_OUT                    1
I2C_EXP_LOC_SDA_R                      1
I2C_EXP_RMT_SCL                        1
I2C_EXP_RMT_SCL_OUT                    1
I2C_EXP_RMT_SCL_R                      1
I2C_EXP_RMT_SDA                        1
I2C_EXP_RMT_SDA_OUT                    1
I2C_EXP_RMT_SDA_R                      1
I2C_IOC_SCL                            1
I2C_IOC_SDA                            1
I2C_IOM_SCL                            1
I2C_IOM_SDA                            1
I2C_M2_1_SCL                           1
I2C_M2_1_SDA                           1
I2C_M2_2_SCL                           1
I2C_M2_2_SDA                           1
I2C_MEZZ_ALERT_N                       1
I2C_MEZZ_ALERT_R_N                     1
I2C_MEZZ_FRU_SENSOR_SCL                1
I2C_MEZZ_FRU_SENSOR_SDA                1
I2C_MEZZ_OOB_SCL                       1
I2C_MEZZ_OOB_SDA                       1
I2C_SCC_SCL                            1
I2C_SCC_SCL_OUT                        1
I2C_SCC_SCL_R                          1
I2C_SCC_SDA                            1
I2C_SCC_SDA_OUT                        1
I2C_SCC_SDA_R                          1
I2C_TPM_SCL                            1
I2C_TPM_SDA                            1
ICE0_TCK                               1
ICE0_TDI                               1
ICE0_TDO                               1
ICE0_TMS                               1
ICE0_TRST#                             1
ICE1_TCK                               1
ICE1_TDI                               1
ICE1_TDO                               1
ICE1_TMS                               1
ICE1_TRST#                             1
ICE_SEL                                1
IOC_CLK_SEL0                           1
IOC_CLK_SEL1                           1
IOC_EEPROM_A0                          1
IOC_EEPROM_A1                          1
IOC_EEPROM_A2                          1
IOC_EEPROM_SCL                         1
IOC_EEPROM_SDA                         1
IOC_EEPROM_WP                          1
IOC_EXT1_LED_B                         1
IOC_EXT1_LED_Y                         1
IOC_EXT1_LED_Y_XOR                     1
IOC_EXT2_LED_B                         1
IOC_EXT2_LED_Y                         1
IOC_EXT2_LED_Y_XOR                     1
IOC_GPIO_0                             1
IOC_GPIO_1                             1
IOC_GPIO_10                            1
IOC_GPIO_11                            1
IOC_GPIO_12                            1
IOC_GPIO_13                            1
IOC_GPIO_14                            1
IOC_GPIO_15                            1
IOC_GPIO_16                            1
IOC_GPIO_17                            1
IOC_GPIO_18                            1
IOC_GPIO_19                            1
IOC_GPIO_2                             1
IOC_GPIO_20                            1
IOC_GPIO_21                            1
IOC_GPIO_22                            1
IOC_GPIO_23                            1
IOC_GPIO_24                            1
IOC_GPIO_25                            1
IOC_GPIO_26                            1
IOC_GPIO_27                            1
IOC_GPIO_28                            1
IOC_GPIO_29                            1
IOC_GPIO_3                             1
IOC_GPIO_30                            1
IOC_GPIO_31                            1
IOC_GPIO_32                            1
IOC_GPIO_33                            1
IOC_GPIO_34                            1
IOC_GPIO_35                            1
IOC_GPIO_4                             1
IOC_GPIO_5                             1
IOC_GPIO_6                             1
IOC_GPIO_7                             1
IOC_GPIO_8                             1
IOC_GPIO_9                             1
IOC_REF_CLK_N                          1
IOC_REF_CLK_P                          1
IOC_RESET#                             1
IOC_SCL_0                              1
IOC_SCL_1                              1
IOC_SCL_2                              1
IOC_SCL_3                              1
IOC_SCL_4                              1
IOC_SDA_0                              1
IOC_SDA_1                              1
IOC_SDA_2                              1
IOC_SDA_3                              1
IOC_SDA_4                              1
IOC_SIO_BLINK                          1
IOC_TDO                                1
IOC_TRST_N                             1
IOC_UART_0_RX                          1
IOC_UART_0_RX_R                        1
IOC_UART_0_TX                          1
IOC_UART_0_TX_R                        1
IOC_UART_1_RX                          1
IOC_UART_1_TX                          1
IOC_UART_R_RX                          1
IOC_UART_R_TX                          1
IOC_VREF_SET                           1
IOC_WP_N                               1
IOM_ADM1278_EN                         1
IOM_FULL_PGOOD                         1
IOM_FULL_PWR_EN                        1
IOM_FULL_PWR_EN_R                      1
IOM_IOC_UART_RX                        1
IOM_IOC_UART_TX                        1
IOM_LOC_INS_N                          1
IOM_MATED_N                            1
IOM_STBY_PGOOD                         1
IOM_TYPE0                              1
IOM_TYPE1                              1
IOM_TYPE2                              1
IOM_TYPE3                              1
IO_EXP0_RESET#_FLT                     1
IRQ_CPU_SERIAL                         1
JTAG_BMC_TCK                           1
JTAG_BMC_TDI                           1
JTAG_BMC_TDO                           1
JTAG_BMC_TMS                           1
JTAG_BMC_TRST_N                        1
JTAG_IOC_TCK                           1
JTAG_IOC_TDI                           1
JTAG_IOC_TMS                           1
LED_POSTCODE_0                         1
LED_POSTCODE_1                         1
LED_POSTCODE_2                         1
LED_POSTCODE_3                         1
LED_POSTCODE_4                         1
LED_POSTCODE_5                         1
LED_POSTCODE_6                         1
LED_POSTCODE_7                         1
LPCRST0_N                              1
LPC_CPU_CLKOUT0                        1
LPC_CPU_FRAME_N                        1
LSI_IDDT                               1
LSI_JTAG_EN_N                          1
LSI_SCAN_EN                            1
LSI_TN                                 1
MAC1_TXD2                              1
MAC1_TXD3                              1
MAC2_TXCTL                             1
MAC2_TXD0                              1
MAC2_TXD1                              1
MAC2_TXD2                              1
MAC2_TXD3                              1
MB0_12V_CTRL_GATE1                     1
MB0_CM_ADR1_R                          1
MB0_CM_ADR2_R                          1
MB0_CM_GATE                            1
MB0_CM_GATE_2                          1
MB0_CM_GATE_R                          1
MB0_CM_OV_R                            1
MB0_CM_SENSE_N                         1
MB0_CM_SENSE_P                         1
MB0_CM_SENSE_R1_N                      1
MB0_CM_SENSE_R1_P                      1
MB0_CM_UV_R                            1
MB0_CM_VOUT_R                          1
MB0_HS_ENABLE                          1
MB0_ISET_R                             1
MB0_ISTART_R                           1
MB0_P12V_MAIN_R                        1
MB0_P12V_PWGIN_R                       1
MB0_PSET_R                             1
MB0_RETRY_R                            1
MB0_SPISS_PD                           1
MB0_TEMP                               1
MB0_TEMP_C                             1
MB0_TEMP_E                             1
MB0_TIME_R                             1
MB0_VCAP_R                             1
MB0_VCC                                1
MEMCK_TER                              1
MEM_CLK_SEL                            1
MEM_PAR                                1
MEZZA_PRSNT1_N                         1
MEZZ_A_PRSNT_120_N                     1
MIOZ                                   1
ML_PWR_BLUE_LED                        1
ML_PWR_BLUE_LED_R                      1
ML_PWR_YELLOW_LED                      1
ML_PWR_YELLOW_LED_R                    1
MPLLAV33                               1
NCSI_RCLK                              1
NCSI_RCLK_R                            1
NCSI_RCSDV                             1
NCSI_RCSDV_R                           1
NCSI_RXD0                              1
NCSI_RXD0_R                            1
NCSI_RXD1                              1
NCSI_RXD1_R                            1
NCSI_RX_ER                             1
NCSI_RX_ER_R                           1
NCSI_TXD0                              1
NCSI_TXD0_R                            1
NCSI_TXD1                              1
NCSI_TXD1_R                            1
NCSI_TXEN                              1
NCSI_TXEN_R                            1
OSC_REF_CLK                            1
P0V975                                 1
P0V975_SEN                             1
P12V_A_PGOOD                           1
P12V_A_PGOOD_R                         1
P12V_IOM                               1
P12V_IOM_PGOOD                         1
P12V_STBY                              1
P12V_STBY_VCC_PU4                      1
P12V_STBY_VDD_PU1                      1
P12V_STBY_VDD_PU2                      1
P12V_STBY_VIN_PU1                      1
P12V_STBY_VIN_PU2                      1
P12V_STBY_VIN_PU4                      1
P1V15_STBY                             1
P1V15_STBY_PG                          1
P1V15_STBY_PG_G                        1
P1V5                                   1
P1V5_OUT                               1
P1V8_EN                                1
P1V8_STBY                              1
P1V8_STBY_CC                           1
P1V8_STBY_CC_R                         1
P1V8_STBY_EN_R                         1
P1V8_STBY_SNB                          1
P1V8_STBY_SS                           1
P1V8_STBY_SW                           1
P1V8_STBY_VBST                         1
P1V8_STBY_VBST_RR                      1
P1V8_STBY_VFB                          1
P1V8_STBY_VFB_R                        1
P1V8_STBY_VO                           1
P1V8_STBY_VRG5                         1
P2V5_STBY                              1
P3V3                                   1
P3V3_EN_R                              1
P3V3_PG                                1
P3V3_SNB                               1
P3V3_STBY_EN                           1
P3V3_STBY_G                            1
P3V3_STBY_LL                           1
P3V3_STBY_LL_R                         1
P3V3_STBY_MODE                         1
P3V3_STBY_RF                           1
P3V3_STBY_TRIP                         1
P3V3_STBY_VFB                          1
P3V3_STBY_VREG                         1
P3V3_VBST                              1
P3V3_VBST_RC                           1
P5V_CC                                 1
P5V_EN_R                               1
P5V_LL                                 1
P5V_LL_R                               1
P5V_MODE                               1
P5V_RF                                 1
P5V_SNB                                1
P5V_STBY_VREG                          1
P5V_TRIP                               1
P5V_VBST                               1
P5V_VBST_RC                            1
P5V_VBUS_CONN                          1
P5V_VFB                                1
P5V_VFB_R                              1
PCE_AVDD                               1
PCE_VDDH                               1
PCIE_COMP_TO_IOM_CLK_3_DN              1
PCIE_COMP_TO_IOM_CLK_3_DP              1
PCIE_COMP_TO_IOM_RST_2                 1
PCIE_COMP_TO_IOM_RST_3                 1
PCIE_COMP_TO_IOM_RST_4                 1
PCIE_COMP_TO_IOM_RST_4_R               1
PCIE_RST_R_N                           1
PCIE_WAKE_N                            1
PD_PERST_N                             1
PD_USB2AVRES                           1
PD_USB2BVRES                           1
PD_ZQ                                  1
PECI                                   1
PLLFILT                                1
PLL_VDD                                1
PLTRST_R                               1
POWERLOSS#                             1
PQ2_D                                  1
PQ2_G                                  1
PQ4_D                                  1
PQ4_G                                  1
PWM_OUT_ZONE_C                         1
PWM_OUT_ZONE_D                         1
PWRBTN_OUT_N_R                         1
PWRGD_P0V975                           1
PWRGD_P1V5                             1
PWRGD_P1V8                             1
PWRGD_P1V8_STBY                        1
PWRGD_P2V5_STBY                        1
PWRGD_P3V3_STBY                        1
PWRGD_P3V3_STBY_N                      1
PWRGD_P3V3_STBY_N_R1                   1
PWRGD_P3V3_STBY_N_R2                   1
PWRGD_P5V_STBY                         1
PWR_BTN_GND                            1
Q6_G                                   1
Q7_G                                   1
Q8_G                                   1
Q9_G                                   1
RMII_BMC_MDC_R                         1
RMII_BMC_MDIO_R                        1
RSTBTN_OUT_N                           1
RSTBTN_OUT_N_R                         1
RST_BMC_EXTRST_N                       1
RST_BMC_EXTRST_N_1                     1
RST_BTN_GND                            1
RTRIM                                  1
RTRIM#                                 1
SAS0_VDDH                              1
SBL_SCL                                1
SBL_SDA                                1
SCC_A_HB_IN_R                          1
SCC_B_HB_IN_R                          1
SCC_LOC_FULLPWR_EN                     1
SCC_LOC_FULL_PWR_EN                    1
SCC_LOC_HEARTBEAT                      1
SCC_PWR_EN_R                           1
SCC_RMT_FULLPWR_EN                     1
SCC_RMT_FULL_PWR_EN                    1
SCC_RMT_HEARTBEAT                      1
SCC_RMT_TYPE_0                         1
SCC_RMT_TYPE_0_R                       1
SCC_STBY_PWR_EN                        1
SHELL_PLL_VDD                          1
SIO_CLK_0                              1
SIO_CLK_1                              1
SIO_DIN_0                              1
SIO_DIN_1                              1
SIO_DOUT_0                             1
SIO_DOUT_1                             1
SIO_LOAD_0                             1
SIO_LOAD_1                             1
SLOTID_0                               1
SLOTID_1                               1
SPARE0                                 1
SPARE1                                 1
SPARE2                                 1
SPARE3                                 1
SPARE4                                 1
SPARE5                                 1
SYS_CORE_TRI#                          1
SYS_DBMODE0                            1
SYS_DBMODE1                            1
SYS_DBMODE2                            1
SYS_DBMODE3                            1
SYS_DBMODE4                            1
SYS_ERROR1                             1
SYS_ERROR_LED_D                        1
SYS_ERROR_LED_R                        1
SYS_ERR_0                              1
SYS_HALT0#                             1
SYS_HALT1#                             1
SYS_HB_LED                             1
SYS_HB_LED_D                           1
SYS_HB_LED_R                           1
SYS_PLL_VDD                            1
SYS_PWR_LED                            1
SYS_RESET_N                            1
SYS_RESET_N_OUT                        1
SYS_RESET_N_OUT_R                      1
SYS_RST_BTN_IN_N                       1
SYS_RST_EN                             1
SYS_RST_N_0                            1
TCA9555_A0                             1
TCA9555_A1                             1
TCA9555_A2                             1
TEMP_3_A0                              1
TEMP_3_A1                              1
TEMP_3_A2                              1
TEMP_3_ALERT                           1
TEMP_3_SCL                             1
TEMP_3_SDA                             1
THROTTLE_N                             1
TPM_PRSNT_N_R                          1
TPS74801_1V5_BIAS                      1
TPS74801_1V5_EN                        1
TPS74801_1V5_SS                        1
TPS74801_P1V15_STBY_BIAS               1
TPS74801_P1V15_STBY_EN                 1
TPS74801_P1V15_STBY_FB                 1
TPS74801_P1V15_STBY_OUT                1
TPS74801_P1V15_STBY_SS                 1
TPS74801_P1V2_STBY_BIAS                1
TPS74801_P1V2_STBY_EN                  1
TPS74801_P1V2_STBY_FB                  1
TPS74801_P1V2_STBY_SS                  1
TPS74801_P1V5_FB                       1
TPS74801_P2V5_STBY_BIAS                1
TPS74801_P2V5_STBY_EN                  1
TPS74801_P2V5_STBY_FB                  1
TPS74801_P2V5_STBY_OUT                 1
TPS74801_P2V5_STBY_SS                  1
TP_BMC0_LPC_LAD0                       1
TP_BMC0_LPC_LAD1                       1
TP_BMC0_LPC_LAD2                       1
TP_BMC0_LPC_LAD3                       1
TP_BMC_EXT1_LED_B                      1
TP_BMC_EXT2_LED_B                      1
TP_BMC_GPIOA0                          1
TP_BMC_GPIOA6                          1
TP_BMC_GPIOA7                          1
TP_BMC_GPIOG5                          1
TP_BMC_GPIOG6                          1
TP_BMC_GPIOI0                          1
TP_BMC_GPIOI1                          1
TP_BMC_GPIOI2                          1
TP_BMC_GPIOI3                          1
TP_BMC_GPIOI4                          1
TP_BMC_GPIOI5                          1
TP_BMC_GPIOI6                          1
TP_BMC_GPIOI7                          1
TP_BMC_GPIOL0                          1
TP_BMC_GPIOL1                          1
TP_BMC_GPIOL2                          1
TP_BMC_GPIOL3                          1
TP_BMC_GPIOL4                          1
TP_BMC_GPIOL5                          1
TP_BMC_GPION2                          1
TP_BMC_GPION3                          1
TP_BMC_GPION4                          1
TP_BMC_GPION5                          1
TP_BMC_GPION6                          1
TP_BMC_GPION7                          1
TP_BMC_GPIOR1                          1
TP_BMC_GPIOR2                          1
TP_BMC_GPIOR3                          1
TP_BMC_GPIOR4                          1
TP_BMC_GPIOR5                          1
TP_BMC_GPIOT0                          1
TP_BMC_GPIOT6                          1
TP_M2_1_ALERT#                         1
TP_M2_2_ALERT#                         1
TP_USB_SDA                             1
U104_EN                                1
U43_VREF2                              1
UART_BMC_COMP_IN_RX                    1
UART_BMC_COMP_IN_RX_R                  1
UART_BMC_RX                            1
UART_BMC_R_RX                          1
UART_BMC_R_TX                          1
UART_BMC_TX                            1
UART_COMP_IN_RX                        1
UART_COMP_IN_RX_AND                    1
UART_COMP_IN_RX_AND_R                  1
UART_COMP_IN_R_RX                      1
UART_COMP_OUT_TX                       1
UART_COMP_OUT_TX_R                     1
UART_COMP_RX                           1
UART_COMP_R_TX                         1
UART_COMP_TX                           1
UART_EXP_BMC_RX                        1
UART_EXP_BMC_RX_R                      1
UART_EXP_BMC_TX                        1
UART_EXP_BMC_TX_R                      1
UART_IOM_RX                            1
UART_IOM_TX                            1
UART_SDB_RX                            1
UART_SDB_TX                            1
UART_SDB_TX_R                          1
UART_SEL_MUX                           1
USB_COMP_DN                            1
USB_COMP_DP                            1
USB_EN_1                               1
USB_EN_2                               1
USB_EN_3                               1
USB_EN_4                               1
USB_OCS_N1                             1
USB_OCS_N2                             1
USB_OCS_N3                             1
USB_OCS_N4                             1
USB_RESET_N                            1
USB_SUSP_IND                           1
V1PLLAV11                              1
VBUS_DET                               1
VDDA_SAS_REF_CLK                       1
VDDIO_15                               1
VPLLAV33                               1
VREF_2V2                               1
VT235_AVDD                             1
VT235_BIAS                             1
VT235_BST                              1
VT235_EN                               1
VT235_IMAX                             1
VT235_IRIP                             1
VT235_PGIN                             1
VT235_VDDH                             1
VT235_VDDL                             1
VT235_VDES                             1
VT235_VDES_RC                          1
VT235_VDES_RCC                         1
VT235_VDES_RR                          1
VT235_VFB                              1
VT235_VREF                             1
VT235_VX                               1
XM_ADDR_0                              1
XM_ADDR_18                             1
XM_ADDR_2                              1
XM_ADDR_22                             1
XM_ADDR_24                             1
XM_ADDR_25                             1
XM_ADDR_4                              1
XM_ADDR_6                              1
XM_ADDR_7                              1
XM_ADDR_8                              1
XM_ALE                                 1
XM_CLE                                 1
XM_CS0_N                               1
XM_F_RST_N                             1
XM_NAND_CS_N                           1
XM_NOR_CS_N                            1
XM_RB                                  1
XM_WE_N                                1
XM_WP                                  1
ZDEF_EXTA_TP_A1                        1
ZDEF_EXTA_TP_A2                        1
ZDEF_EXTA_TP_B1                        1
ZDEF_EXTA_TP_B2                        1
ZDEF_EXTA_TP_C1                        1
ZDEF_EXTA_TP_C2                        1
ZDEF_EXTA_TP_D1                        1
ZDEF_EXTA_TP_D2                        1
ZDEF_EXTB_TP_A1                        1
ZDEF_EXTB_TP_A2                        1
ZDEF_EXTB_TP_B1                        1
ZDEF_EXTB_TP_B2                        1
ZDEF_EXTB_TP_C1                        1
ZDEF_EXTB_TP_C2                        1
ZDEF_EXTB_TP_D1                        1
ZDEF_EXTB_TP_D2                        1

50M_CLK_OUT                            0
50M_CLK_OUT_R                          0
BMC_CPU_DIS                            0
BMC_CPU_EN                             0
BMC_GPIOZ7                             0
BMC_SPI_MISO                           0
BMC_SPI_MISO_TPM                       0
CLKIN_24M_BMC                          0
DDR4_ACT                               0
DDR4_ALERT                             0
DDR4_RST_N                             0
FLA0_SPI_HOLD_N                        0
FLA0_SPI_RST                           0
FLA1_SPI_RST                           0
FM_OSC_50M_EN                          0
I2C_DEBUG_SCL_R                        0
I2C_DEBUG_SDA_R                        0
MEMA_0                                 0
MEMA_1                                 0
MEMA_10                                0
MEMA_11                                0
MEMA_12                                0
MEMA_13                                0
MEMA_2                                 0
MEMA_3                                 0
MEMA_4                                 0
MEMA_5                                 0
MEMA_6                                 0
MEMA_7                                 0
MEMA_8                                 0
MEMA_9                                 0
MEMBA_0                                0
MEMBA_1                                0
MEMBG_0                                0
MEMCASN                                0
MEMCKE                                 0
MEMCK_N                                0
MEMCK_P                                0
MEMCSN                                 0
MEMDM_0                                0
MEMDM_1                                0
MEMDQS_N0                              0
MEMDQS_N1                              0
MEMDQS_P0                              0
MEMDQS_P1                              0
MEMDQ_0                                0
MEMDQ_1                                0
MEMDQ_10                               0
MEMDQ_11                               0
MEMDQ_12                               0
MEMDQ_13                               0
MEMDQ_14                               0
MEMDQ_15                               0
MEMDQ_2                                0
MEMDQ_3                                0
MEMDQ_4                                0
MEMDQ_5                                0
MEMDQ_6                                0
MEMDQ_7                                0
MEMDQ_8                                0
MEMDQ_9                                0
MEMODT                                 0
MEMRASN                                0
MEMWEN                                 0
N62640349                              0
OSC_OE                                 0
OSC_OUT                                0
P3V3_EN                                0
P3V3_STBY_ROVP                         0
P3V3_STBY_VFB_R                        0
P5V_USB                                0
PCIE_COMP_TO_IOM_10_DN                 0
PCIE_COMP_TO_IOM_10_DP                 0
PCIE_COMP_TO_IOM_11_DN                 0
PCIE_COMP_TO_IOM_11_DP                 0
PCIE_COMP_TO_IOM_12_DN                 0
PCIE_COMP_TO_IOM_12_DP                 0
PCIE_COMP_TO_IOM_13_DN                 0
PCIE_COMP_TO_IOM_13_DP                 0
PCIE_COMP_TO_IOM_14_DN                 0
PCIE_COMP_TO_IOM_14_DP                 0
PCIE_COMP_TO_IOM_15_DN                 0
PCIE_COMP_TO_IOM_15_DP                 0
PCIE_COMP_TO_IOM_16_DN                 0
PCIE_COMP_TO_IOM_16_DP                 0
PCIE_COMP_TO_IOM_17_DN                 0
PCIE_COMP_TO_IOM_17_DP                 0
PCIE_COMP_TO_IOM_18_DN                 0
PCIE_COMP_TO_IOM_18_DP                 0
PCIE_COMP_TO_IOM_19_DN                 0
PCIE_COMP_TO_IOM_19_DP                 0
PCIE_COMP_TO_IOM_20_DN                 0
PCIE_COMP_TO_IOM_20_DP                 0
PCIE_COMP_TO_IOM_21_DN                 0
PCIE_COMP_TO_IOM_21_DP                 0
PCIE_COMP_TO_IOM_22_DN                 0
PCIE_COMP_TO_IOM_22_DP                 0
PCIE_COMP_TO_IOM_23_DN                 0
PCIE_COMP_TO_IOM_23_DP                 0
PCIE_COMP_TO_IOM_8_DN                  0
PCIE_COMP_TO_IOM_8_DP                  0
PCIE_COMP_TO_IOM_9_DN                  0
PCIE_COMP_TO_IOM_9_DP                  0
PCIE_COMP_TO_IOM_CLK_2_DN              0
PCIE_COMP_TO_IOM_CLK_2_DP              0
PCIE_COMP_TO_IOM_CLK_4_DN              0
PCIE_COMP_TO_IOM_CLK_4_DP              0
PCIE_IOM_TO_COMP_10_DN                 0
PCIE_IOM_TO_COMP_10_DN_C               0
PCIE_IOM_TO_COMP_10_DP                 0
PCIE_IOM_TO_COMP_10_DP_C               0
PCIE_IOM_TO_COMP_11_DN                 0
PCIE_IOM_TO_COMP_11_DN_C               0
PCIE_IOM_TO_COMP_11_DP                 0
PCIE_IOM_TO_COMP_11_DP_C               0
PCIE_IOM_TO_COMP_12_DN                 0
PCIE_IOM_TO_COMP_12_DN_C               0
PCIE_IOM_TO_COMP_12_DP                 0
PCIE_IOM_TO_COMP_12_DP_C               0
PCIE_IOM_TO_COMP_13_DN                 0
PCIE_IOM_TO_COMP_13_DN_C               0
PCIE_IOM_TO_COMP_13_DP                 0
PCIE_IOM_TO_COMP_13_DP_C               0
PCIE_IOM_TO_COMP_14_DN                 0
PCIE_IOM_TO_COMP_14_DN_C               0
PCIE_IOM_TO_COMP_14_DP                 0
PCIE_IOM_TO_COMP_14_DP_C               0
PCIE_IOM_TO_COMP_15_DN                 0
PCIE_IOM_TO_COMP_15_DN_C               0
PCIE_IOM_TO_COMP_15_DP                 0
PCIE_IOM_TO_COMP_15_DP_C               0
PCIE_IOM_TO_COMP_16_DN                 0
PCIE_IOM_TO_COMP_16_DP                 0
PCIE_IOM_TO_COMP_17_DN                 0
PCIE_IOM_TO_COMP_17_DP                 0
PCIE_IOM_TO_COMP_18_DN                 0
PCIE_IOM_TO_COMP_18_DP                 0
PCIE_IOM_TO_COMP_19_DN                 0
PCIE_IOM_TO_COMP_19_DP                 0
PCIE_IOM_TO_COMP_20_DN                 0
PCIE_IOM_TO_COMP_20_DP                 0
PCIE_IOM_TO_COMP_21_DN                 0
PCIE_IOM_TO_COMP_21_DP                 0
PCIE_IOM_TO_COMP_22_DN                 0
PCIE_IOM_TO_COMP_22_DP                 0
PCIE_IOM_TO_COMP_23_DN                 0
PCIE_IOM_TO_COMP_23_DP                 0
PCIE_IOM_TO_COMP_8_DN                  0
PCIE_IOM_TO_COMP_8_DN_C                0
PCIE_IOM_TO_COMP_8_DP                  0
PCIE_IOM_TO_COMP_8_DP_C                0
PCIE_IOM_TO_COMP_9_DN                  0
PCIE_IOM_TO_COMP_9_DN_C                0
PCIE_IOM_TO_COMP_9_DP                  0
PCIE_IOM_TO_COMP_9_DP_C                0
PHY_CON_A_TO_IOC_0_DN                  0
PHY_CON_A_TO_IOC_0_DN_C                0
PHY_CON_A_TO_IOC_0_DP                  0
PHY_CON_A_TO_IOC_0_DP_C                0
PHY_CON_A_TO_IOC_1_DN                  0
PHY_CON_A_TO_IOC_1_DN_C                0
PHY_CON_A_TO_IOC_1_DP                  0
PHY_CON_A_TO_IOC_1_DP_C                0
PHY_CON_A_TO_IOC_2_DN                  0
PHY_CON_A_TO_IOC_2_DN_C                0
PHY_CON_A_TO_IOC_2_DP                  0
PHY_CON_A_TO_IOC_2_DP_C                0
PHY_CON_A_TO_IOC_3_DN                  0
PHY_CON_A_TO_IOC_3_DN_C                0
PHY_CON_A_TO_IOC_3_DP                  0
PHY_CON_A_TO_IOC_3_DP_C                0
PHY_CON_B_TO_IOC_0_DN                  0
PHY_CON_B_TO_IOC_0_DN_C                0
PHY_CON_B_TO_IOC_0_DP                  0
PHY_CON_B_TO_IOC_0_DP_C                0
PHY_CON_B_TO_IOC_1_DN                  0
PHY_CON_B_TO_IOC_1_DN_C                0
PHY_CON_B_TO_IOC_1_DP                  0
PHY_CON_B_TO_IOC_1_DP_C                0
PHY_CON_B_TO_IOC_2_DN                  0
PHY_CON_B_TO_IOC_2_DN_C                0
PHY_CON_B_TO_IOC_2_DP                  0
PHY_CON_B_TO_IOC_2_DP_C                0
PHY_CON_B_TO_IOC_3_DN                  0
PHY_CON_B_TO_IOC_3_DN_C                0
PHY_CON_B_TO_IOC_3_DP                  0
PHY_CON_B_TO_IOC_3_DP_C                0
PHY_IOC_TO_CON_A_0_DN                  0
PHY_IOC_TO_CON_A_0_DN_C                0
PHY_IOC_TO_CON_A_0_DP                  0
PHY_IOC_TO_CON_A_0_DP_C                0
PHY_IOC_TO_CON_A_1_DN                  0
PHY_IOC_TO_CON_A_1_DN_C                0
PHY_IOC_TO_CON_A_1_DP                  0
PHY_IOC_TO_CON_A_1_DP_C                0
PHY_IOC_TO_CON_A_2_DN                  0
PHY_IOC_TO_CON_A_2_DN_C                0
PHY_IOC_TO_CON_A_2_DP                  0
PHY_IOC_TO_CON_A_2_DP_C                0
PHY_IOC_TO_CON_A_3_DN                  0
PHY_IOC_TO_CON_A_3_DN_C                0
PHY_IOC_TO_CON_A_3_DP                  0
PHY_IOC_TO_CON_A_3_DP_C                0
PHY_IOC_TO_CON_B_0_DN                  0
PHY_IOC_TO_CON_B_0_DN_C                0
PHY_IOC_TO_CON_B_0_DP                  0
PHY_IOC_TO_CON_B_0_DP_C                0
PHY_IOC_TO_CON_B_1_DN                  0
PHY_IOC_TO_CON_B_1_DN_C                0
PHY_IOC_TO_CON_B_1_DP                  0
PHY_IOC_TO_CON_B_1_DP_C                0
PHY_IOC_TO_CON_B_2_DN                  0
PHY_IOC_TO_CON_B_2_DN_C                0
PHY_IOC_TO_CON_B_2_DP                  0
PHY_IOC_TO_CON_B_2_DP_C                0
PHY_IOC_TO_CON_B_3_DN                  0
PHY_IOC_TO_CON_B_3_DN_C                0
PHY_IOC_TO_CON_B_3_DP                  0
PHY_IOC_TO_CON_B_3_DP_C                0
PU_IBMC_BT_HOLD_N                      0
Q4_G                                   0
RBIAS                                  0
REF_CLK                                0
SYS_RST_N_1                            0
U30_Q1                                 0
UART_COMP_R_RX                         0
USB_HUB_XTAL_IN                        0
USB_HUB_XTAL_OUT                       0
USB_P1_DN                              0
USB_P1_DP                              0
USB_P1_F_DN1                           0
USB_P1_F_DP1                           0
USB_P2_DN                              0
USB_P2_DP                              0
USB_P3_DN                              0
USB_P3_DP                              0
WP_DISABLE                             0
WP_ENABLE                              0
XM_ADDR_1                              0
XM_ADDR_10                             0
XM_ADDR_11                             0
XM_ADDR_12                             0
XM_ADDR_13                             0
XM_ADDR_14                             0
XM_ADDR_15                             0
XM_ADDR_16                             0
XM_ADDR_17                             0
XM_ADDR_19                             0
XM_ADDR_20                             0
XM_ADDR_21                             0
XM_ADDR_23                             0
XM_ADDR_3                              0
XM_ADDR_5                              0
XM_ADDR_9                              0
XM_DATA_0                              0
XM_DATA_1                              0
XM_DATA_10                             0
XM_DATA_11                             0
XM_DATA_12                             0
XM_DATA_13                             0
XM_DATA_14                             0
XM_DATA_15                             0
XM_DATA_2                              0
XM_DATA_3                              0
XM_DATA_4                              0
XM_DATA_5                              0
XM_DATA_6                              0
XM_DATA_7                              0
XM_DATA_8                              0
XM_DATA_9                              0
XM_OE_N                                0
